(kicad_pcb
	(version 20260206)
	(generator "pcbnew")
	(generator_version "10.0")
	(general
		(thickness 1.6)
		(legacy_teardrops no)
	)
	(paper "A4")
	(title_block
		(title "03242023_DA0F0TMBIJ0_F0T_Motherboard_J_brd_V01_OCP.brd")
		(comment 1 "Grand Teton / footprints 4729-4734 of 6105")
	)
	(layers
		(0 "F.Cu" signal "TOP")
		(4 "In1.Cu" signal "GND")
		(6 "In2.Cu" signal "IN1")
		(8 "In3.Cu" signal "GND1")
		(10 "In4.Cu" signal "IN2")
		(12 "In5.Cu" signal "GND2")
		(14 "In6.Cu" signal "IN3")
		(16 "In7.Cu" signal "GND3")
		(18 "In8.Cu" signal "VCC")
		(20 "In9.Cu" signal "VCC1")
		(22 "In10.Cu" signal "GND4")
		(24 "In11.Cu" signal "IN4")
		(26 "In12.Cu" signal "GND5")
		(28 "In13.Cu" signal "IN5")
		(30 "In14.Cu" signal "GND6")
		(32 "In15.Cu" signal "IN6")
		(34 "In16.Cu" signal "GND7")
		(2 "B.Cu" signal "BOTTOM")
		(9 "F.Adhes" user "F.Adhesive")
		(11 "B.Adhes" user "B.Adhesive")
		(13 "F.Paste" user "Package Geometry/Pastemask Top")
		(15 "B.Paste" user "Package Geometry/Pastemask Bottom")
		(5 "F.SilkS" user "Ref Des/Silkscreen Top")
		(7 "B.SilkS" user "Ref Des/Silkscreen Bottom")
		(1 "F.Mask" user "Board Geometry/Soldermask Top")
		(3 "B.Mask" user "Board Geometry/Soldermask Bottom")
		(17 "Dwgs.User" user "User.Drawings")
		(19 "Cmts.User" user "User.Comments")
		(21 "Eco1.User" user "User.Eco1")
		(23 "Eco2.User" user "User.Eco2")
		(25 "Edge.Cuts" user "Board Geometry/Outline")
		(27 "Margin" user)
		(31 "F.CrtYd" user "Package Geometry/Place Bound Top")
		(29 "B.CrtYd" user "Package Geometry/Place Bound Bottom")
		(35 "F.Fab" user "Ref Des/Assembly Top")
		(33 "B.Fab" user "Ref Des/Assembly Bottom")
	)
	(footprint ""
		(layer "B.Cu")
		(at 340.033864 -337.145884 90)
		(property "Reference" "PC260_P0_6"
			(at 0 0 90)
			(layer "B.SilkS")
			(hide yes)
			(effects
				(font
					(size 1.27 1.27)
				)
				(justify mirror)
			)
		)
		(property "Value" ""
			(at 0 0 90)
			(layer "B.Fab")
			(effects
				(font
					(size 1.27 1.27)
				)
				(justify mirror)
			)
		)
		(duplicate_pad_numbers_are_jumpers no)
		(fp_line
			(start 1.524 -0.762)
			(end -1.524 -0.762)
			(stroke
				(width 0.1524)
				(type default)
			)
			(layer "B.SilkS")
		)
		(fp_line
			(start -1.524 -0.762)
			(end -1.524 0.762)
			(stroke
				(width 0.1524)
				(type default)
			)
			(layer "B.SilkS")
		)
		(fp_line
			(start 1.524 0.762)
			(end 1.524 -0.762)
			(stroke
				(width 0.1524)
				(type default)
			)
			(layer "B.SilkS")
		)
		(fp_line
			(start -1.524 0.762)
			(end 1.524 0.762)
			(stroke
				(width 0.1524)
				(type default)
			)
			(layer "B.SilkS")
		)
		(fp_line
			(start 1.1049 -0.724916)
			(end 1.1049 0.724916)
			(stroke
				(width 0.1)
				(type default)
			)
			(layer "B.Fab")
		)
		(fp_line
			(start -1.1049 -0.724916)
			(end 1.1049 -0.724916)
			(stroke
				(width 0.1)
				(type default)
			)
			(layer "B.Fab")
		)
		(fp_line
			(start 1.1049 0.724916)
			(end -1.1049 0.724916)
			(stroke
				(width 0.1)
				(type default)
			)
			(layer "B.Fab")
		)
		(fp_line
			(start -1.1049 0.724916)
			(end -1.1049 -0.724916)
			(stroke
				(width 0.1)
				(type default)
			)
			(layer "B.Fab")
		)
		(pad "1" smd rect
			(at 0.889 0 90)
			(size 1.016 1.27)
			(layers "B.Cu" "B.Mask" "B.Paste")
			(net "SW_P12V_PVCCIN_CPU0_FLT")
		)
		(pad "2" smd rect
			(at -0.889 0 90)
			(size 1.016 1.27)
			(layers "B.Cu" "B.Mask" "B.Paste")
			(net "GND")
		)
	)
	(footprint ""
		(layer "B.Cu")
		(at 322.080382 -38.794944 45)
		(property "Reference" "R1736"
			(at 0 0 45)
			(layer "B.SilkS")
			(hide yes)
			(effects
				(font
					(size 1.27 1.27)
				)
				(justify mirror)
			)
		)
		(property "Value" ""
			(at 0 0 45)
			(layer "B.Fab")
			(effects
				(font
					(size 1.27 1.27)
				)
				(justify mirror)
			)
		)
		(duplicate_pad_numbers_are_jumpers no)
		(fp_line
			(start -0.787389 -0.406267)
			(end -0.787389 0.406267)
			(stroke
				(width 0.1524)
				(type default)
			)
			(layer "B.SilkS")
		)
		(fp_line
			(start -0.787389 0.406267)
			(end 0.787389 0.406267)
			(stroke
				(width 0.1524)
				(type default)
			)
			(layer "B.SilkS")
		)
		(fp_line
			(start 0.787389 -0.406267)
			(end -0.787389 -0.406267)
			(stroke
				(width 0.1524)
				(type default)
			)
			(layer "B.SilkS")
		)
		(fp_line
			(start 0.787389 0.406267)
			(end 0.787389 -0.406267)
			(stroke
				(width 0.1524)
				(type default)
			)
			(layer "B.SilkS")
		)
		(fp_line
			(start -0.679446 -0.30479)
			(end -0.679446 0.30479)
			(stroke
				(width 0.1)
				(type default)
			)
			(layer "B.Fab")
		)
		(fp_line
			(start -0.120515 -0.30479)
			(end -0.679446 -0.30479)
			(stroke
				(width 0.1)
				(type default)
			)
			(layer "B.Fab")
		)
		(fp_line
			(start -0.120695 -0.279466)
			(end -0.120515 -0.30479)
			(stroke
				(width 0.1)
				(type default)
			)
			(layer "B.Fab")
		)
		(fp_line
			(start -0.679446 0.30479)
			(end -0.120515 0.30479)
			(stroke
				(width 0.1)
				(type default)
			)
			(layer "B.Fab")
		)
		(fp_line
			(start 0.120695 -0.304969)
			(end 0.120695 -0.279466)
			(stroke
				(width 0.1)
				(type default)
			)
			(layer "B.Fab")
		)
		(fp_line
			(start 0.120695 -0.279466)
			(end -0.120695 -0.279466)
			(stroke
				(width 0.1)
				(type default)
			)
			(layer "B.Fab")
		)
		(fp_line
			(start -0.120335 0.279466)
			(end 0.120695 0.279466)
			(stroke
				(width 0.1)
				(type default)
			)
			(layer "B.Fab")
		)
		(fp_line
			(start -0.120515 0.30479)
			(end -0.120335 0.279466)
			(stroke
				(width 0.1)
				(type default)
			)
			(layer "B.Fab")
		)
		(fp_line
			(start 0.679446 -0.305149)
			(end 0.120695 -0.304969)
			(stroke
				(width 0.1)
				(type default)
			)
			(layer "B.Fab")
		)
		(fp_line
			(start 0.120695 0.279466)
			(end 0.120515 0.30479)
			(stroke
				(width 0.1)
				(type default)
			)
			(layer "B.Fab")
		)
		(fp_line
			(start 0.120515 0.30479)
			(end 0.679446 0.30479)
			(stroke
				(width 0.1)
				(type default)
			)
			(layer "B.Fab")
		)
		(fp_line
			(start 0.679446 0.30479)
			(end 0.679446 -0.305149)
			(stroke
				(width 0.1)
				(type default)
			)
			(layer "B.Fab")
		)
		(pad "1" smd circle
			(at 0.40005 0 225)
			(size 0 0)
			(layers "B.Cu" "B.Mask" "B.Paste")
			(net "FM_PCH_SLP_SUS_N")
		)
		(pad "2" smd circle
			(at -0.40005 0 225)
			(size 0 0)
			(layers "B.Cu" "B.Mask" "B.Paste")
			(net "FM_SLP_SUS_RSM_RST_N")
		)
	)
	(footprint ""
		(layer "B.Cu")
		(at 333.653638 -188.92393 -90)
		(property "Reference" "R18"
			(at 0 0 90)
			(layer "B.SilkS")
			(hide yes)
			(effects
				(font
					(size 1.27 1.27)
				)
				(justify mirror)
			)
		)
		(property "Value" ""
			(at 0 0 90)
			(layer "B.Fab")
			(effects
				(font
					(size 1.27 1.27)
				)
				(justify mirror)
			)
		)
		(duplicate_pad_numbers_are_jumpers no)
		(fp_line
			(start -0.7874 0.4064)
			(end 0.7874 0.4064)
			(stroke
				(width 0.1524)
				(type default)
			)
			(layer "B.SilkS")
		)
		(fp_line
			(start 0.7874 0.4064)
			(end 0.7874 -0.4064)
			(stroke
				(width 0.1524)
				(type default)
			)
			(layer "B.SilkS")
		)
		(fp_line
			(start -0.7874 -0.4064)
			(end -0.7874 0.4064)
			(stroke
				(width 0.1524)
				(type default)
			)
			(layer "B.SilkS")
		)
		(fp_line
			(start 0.7874 -0.4064)
			(end -0.7874 -0.4064)
			(stroke
				(width 0.1524)
				(type default)
			)
			(layer "B.SilkS")
		)
		(fp_line
			(start -0.67945 0.3048)
			(end -0.120396 0.3048)
			(stroke
				(width 0.1)
				(type default)
			)
			(layer "B.Fab")
		)
		(fp_line
			(start -0.120396 0.3048)
			(end -0.120396 0.2794)
			(stroke
				(width 0.1)
				(type default)
			)
			(layer "B.Fab")
		)
		(fp_line
			(start 0.12065 0.3048)
			(end 0.67945 0.3048)
			(stroke
				(width 0.1)
				(type default)
			)
			(layer "B.Fab")
		)
		(fp_line
			(start 0.67945 0.3048)
			(end 0.67945 -0.305054)
			(stroke
				(width 0.1)
				(type default)
			)
			(layer "B.Fab")
		)
		(fp_line
			(start -0.120396 0.2794)
			(end 0.12065 0.2794)
			(stroke
				(width 0.1)
				(type default)
			)
			(layer "B.Fab")
		)
		(fp_line
			(start 0.12065 0.2794)
			(end 0.12065 0.3048)
			(stroke
				(width 0.1)
				(type default)
			)
			(layer "B.Fab")
		)
		(fp_line
			(start -0.12065 -0.2794)
			(end -0.12065 -0.3048)
			(stroke
				(width 0.1)
				(type default)
			)
			(layer "B.Fab")
		)
		(fp_line
			(start 0.12065 -0.2794)
			(end -0.12065 -0.2794)
			(stroke
				(width 0.1)
				(type default)
			)
			(layer "B.Fab")
		)
		(fp_line
			(start -0.67945 -0.3048)
			(end -0.67945 0.3048)
			(stroke
				(width 0.1)
				(type default)
			)
			(layer "B.Fab")
		)
		(fp_line
			(start -0.12065 -0.3048)
			(end -0.67945 -0.3048)
			(stroke
				(width 0.1)
				(type default)
			)
			(layer "B.Fab")
		)
		(fp_line
			(start 0.12065 -0.305054)
			(end 0.12065 -0.2794)
			(stroke
				(width 0.1)
				(type default)
			)
			(layer "B.Fab")
		)
		(fp_line
			(start 0.67945 -0.305054)
			(end 0.12065 -0.305054)
			(stroke
				(width 0.1)
				(type default)
			)
			(layer "B.Fab")
		)
		(pad "1" smd circle
			(at 0.40005 0 90)
			(size 0 0)
			(layers "B.Cu" "B.Mask" "B.Paste")
			(net "PVNN_TERM_CPU0")
		)
		(pad "2" smd circle
			(at -0.40005 0 90)
			(size 0 0)
			(layers "B.Cu" "B.Mask" "B.Paste")
			(net "DBP_CPU_MBP0_GTL_N")
		)
	)
	(footprint ""
		(layer "B.Cu")
		(at 347.32468 -325.135748 -90)
		(property "Reference" "PR4219"
			(at 0 0 90)
			(layer "B.SilkS")
			(hide yes)
			(effects
				(font
					(size 1.27 1.27)
				)
				(justify mirror)
			)
		)
		(property "Value" ""
			(at 0 0 90)
			(layer "B.Fab")
			(effects
				(font
					(size 1.27 1.27)
				)
				(justify mirror)
			)
		)
		(duplicate_pad_numbers_are_jumpers no)
		(fp_line
			(start -0.7874 0.4064)
			(end 0.7874 0.4064)
			(stroke
				(width 0.1524)
				(type default)
			)
			(layer "B.SilkS")
		)
		(fp_line
			(start 0.7874 0.4064)
			(end 0.7874 -0.4064)
			(stroke
				(width 0.1524)
				(type default)
			)
			(layer "B.SilkS")
		)
		(fp_line
			(start -0.7874 -0.4064)
			(end -0.7874 0.4064)
			(stroke
				(width 0.1524)
				(type default)
			)
			(layer "B.SilkS")
		)
		(fp_line
			(start 0.7874 -0.4064)
			(end -0.7874 -0.4064)
			(stroke
				(width 0.1524)
				(type default)
			)
			(layer "B.SilkS")
		)
		(fp_line
			(start -0.67945 0.3048)
			(end -0.120396 0.3048)
			(stroke
				(width 0.1)
				(type default)
			)
			(layer "B.Fab")
		)
		(fp_line
			(start -0.120396 0.3048)
			(end -0.120396 0.2794)
			(stroke
				(width 0.1)
				(type default)
			)
			(layer "B.Fab")
		)
		(fp_line
			(start 0.12065 0.3048)
			(end 0.67945 0.3048)
			(stroke
				(width 0.1)
				(type default)
			)
			(layer "B.Fab")
		)
		(fp_line
			(start 0.67945 0.3048)
			(end 0.67945 -0.305054)
			(stroke
				(width 0.1)
				(type default)
			)
			(layer "B.Fab")
		)
		(fp_line
			(start -0.120396 0.2794)
			(end 0.12065 0.2794)
			(stroke
				(width 0.1)
				(type default)
			)
			(layer "B.Fab")
		)
		(fp_line
			(start 0.12065 0.2794)
			(end 0.12065 0.3048)
			(stroke
				(width 0.1)
				(type default)
			)
			(layer "B.Fab")
		)
		(fp_line
			(start -0.12065 -0.2794)
			(end -0.12065 -0.3048)
			(stroke
				(width 0.1)
				(type default)
			)
			(layer "B.Fab")
		)
		(fp_line
			(start 0.12065 -0.2794)
			(end -0.12065 -0.2794)
			(stroke
				(width 0.1)
				(type default)
			)
			(layer "B.Fab")
		)
		(fp_line
			(start -0.67945 -0.3048)
			(end -0.67945 0.3048)
			(stroke
				(width 0.1)
				(type default)
			)
			(layer "B.Fab")
		)
		(fp_line
			(start -0.12065 -0.3048)
			(end -0.67945 -0.3048)
			(stroke
				(width 0.1)
				(type default)
			)
			(layer "B.Fab")
		)
		(fp_line
			(start 0.12065 -0.305054)
			(end 0.12065 -0.2794)
			(stroke
				(width 0.1)
				(type default)
			)
			(layer "B.Fab")
		)
		(fp_line
			(start 0.67945 -0.305054)
			(end 0.12065 -0.305054)
			(stroke
				(width 0.1)
				(type default)
			)
			(layer "B.Fab")
		)
		(pad "1" smd circle
			(at 0.40005 0 90)
			(size 0 0)
			(layers "B.Cu" "B.Mask" "B.Paste")
			(net "PVCCIN_CPU0")
		)
		(pad "2" smd circle
			(at -0.40005 0 90)
			(size 0 0)
			(layers "B.Cu" "B.Mask" "B.Paste")
			(net "GND")
		)
	)
	(footprint ""
		(layer "B.Cu")
		(at 83.082384 -188.035692 -90)
		(property "Reference" "R263"
			(at 0 0 90)
			(layer "B.SilkS")
			(hide yes)
			(effects
				(font
					(size 1.27 1.27)
				)
				(justify mirror)
			)
		)
		(property "Value" ""
			(at 0 0 90)
			(layer "B.Fab")
			(effects
				(font
					(size 1.27 1.27)
				)
				(justify mirror)
			)
		)
		(duplicate_pad_numbers_are_jumpers no)
		(fp_line
			(start -0.7874 0.4064)
			(end 0.7874 0.4064)
			(stroke
				(width 0.1524)
				(type default)
			)
			(layer "B.SilkS")
		)
		(fp_line
			(start 0.7874 0.4064)
			(end 0.7874 -0.4064)
			(stroke
				(width 0.1524)
				(type default)
			)
			(layer "B.SilkS")
		)
		(fp_line
			(start -0.7874 -0.4064)
			(end -0.7874 0.4064)
			(stroke
				(width 0.1524)
				(type default)
			)
			(layer "B.SilkS")
		)
		(fp_line
			(start 0.7874 -0.4064)
			(end -0.7874 -0.4064)
			(stroke
				(width 0.1524)
				(type default)
			)
			(layer "B.SilkS")
		)
		(fp_line
			(start -0.67945 0.3048)
			(end -0.120396 0.3048)
			(stroke
				(width 0.1)
				(type default)
			)
			(layer "B.Fab")
		)
		(fp_line
			(start -0.120396 0.3048)
			(end -0.120396 0.2794)
			(stroke
				(width 0.1)
				(type default)
			)
			(layer "B.Fab")
		)
		(fp_line
			(start 0.12065 0.3048)
			(end 0.67945 0.3048)
			(stroke
				(width 0.1)
				(type default)
			)
			(layer "B.Fab")
		)
		(fp_line
			(start 0.67945 0.3048)
			(end 0.67945 -0.305054)
			(stroke
				(width 0.1)
				(type default)
			)
			(layer "B.Fab")
		)
		(fp_line
			(start -0.120396 0.2794)
			(end 0.12065 0.2794)
			(stroke
				(width 0.1)
				(type default)
			)
			(layer "B.Fab")
		)
		(fp_line
			(start 0.12065 0.2794)
			(end 0.12065 0.3048)
			(stroke
				(width 0.1)
				(type default)
			)
			(layer "B.Fab")
		)
		(fp_line
			(start -0.12065 -0.2794)
			(end -0.12065 -0.3048)
			(stroke
				(width 0.1)
				(type default)
			)
			(layer "B.Fab")
		)
		(fp_line
			(start 0.12065 -0.2794)
			(end -0.12065 -0.2794)
			(stroke
				(width 0.1)
				(type default)
			)
			(layer "B.Fab")
		)
		(fp_line
			(start -0.67945 -0.3048)
			(end -0.67945 0.3048)
			(stroke
				(width 0.1)
				(type default)
			)
			(layer "B.Fab")
		)
		(fp_line
			(start -0.12065 -0.3048)
			(end -0.67945 -0.3048)
			(stroke
				(width 0.1)
				(type default)
			)
			(layer "B.Fab")
		)
		(fp_line
			(start 0.12065 -0.305054)
			(end 0.12065 -0.2794)
			(stroke
				(width 0.1)
				(type default)
			)
			(layer "B.Fab")
		)
		(fp_line
			(start 0.67945 -0.305054)
			(end 0.12065 -0.305054)
			(stroke
				(width 0.1)
				(type default)
			)
			(layer "B.Fab")
		)
		(pad "1" smd circle
			(at 0.40005 0 90)
			(size 0 0)
			(layers "B.Cu" "B.Mask" "B.Paste")
			(net "PVNN_TERM_CPU1")
		)
		(pad "2" smd circle
			(at -0.40005 0 90)
			(size 0 0)
			(layers "B.Cu" "B.Mask" "B.Paste")
			(net "PU_CPU1_FRMAGENT")
		)
	)
	(footprint ""
		(layer "B.Cu")
		(at 289.988498 -400.999452 -90)
		(property "Reference" "PR2525"
			(at 0 0 90)
			(layer "B.SilkS")
			(hide yes)
			(effects
				(font
					(size 1.27 1.27)
				)
				(justify mirror)
			)
		)
		(property "Value" ""
			(at 0 0 90)
			(layer "B.Fab")
			(effects
				(font
					(size 1.27 1.27)
				)
				(justify mirror)
			)
		)
		(duplicate_pad_numbers_are_jumpers no)
		(fp_line
			(start -0.7874 0.4064)
			(end 0.7874 0.4064)
			(stroke
				(width 0.1524)
				(type default)
			)
			(layer "B.SilkS")
		)
		(fp_line
			(start 0.7874 0.4064)
			(end 0.7874 -0.4064)
			(stroke
				(width 0.1524)
				(type default)
			)
			(layer "B.SilkS")
		)
		(fp_line
			(start -0.7874 -0.4064)
			(end -0.7874 0.4064)
			(stroke
				(width 0.1524)
				(type default)
			)
			(layer "B.SilkS")
		)
		(fp_line
			(start 0.7874 -0.4064)
			(end -0.7874 -0.4064)
			(stroke
				(width 0.1524)
				(type default)
			)
			(layer "B.SilkS")
		)
		(fp_line
			(start -0.67945 0.3048)
			(end -0.120396 0.3048)
			(stroke
				(width 0.1)
				(type default)
			)
			(layer "B.Fab")
		)
		(fp_line
			(start -0.120396 0.3048)
			(end -0.120396 0.2794)
			(stroke
				(width 0.1)
				(type default)
			)
			(layer "B.Fab")
		)
		(fp_line
			(start 0.12065 0.3048)
			(end 0.67945 0.3048)
			(stroke
				(width 0.1)
				(type default)
			)
			(layer "B.Fab")
		)
		(fp_line
			(start 0.67945 0.3048)
			(end 0.67945 -0.305054)
			(stroke
				(width 0.1)
				(type default)
			)
			(layer "B.Fab")
		)
		(fp_line
			(start -0.120396 0.2794)
			(end 0.12065 0.2794)
			(stroke
				(width 0.1)
				(type default)
			)
			(layer "B.Fab")
		)
		(fp_line
			(start 0.12065 0.2794)
			(end 0.12065 0.3048)
			(stroke
				(width 0.1)
				(type default)
			)
			(layer "B.Fab")
		)
		(fp_line
			(start -0.12065 -0.2794)
			(end -0.12065 -0.3048)
			(stroke
				(width 0.1)
				(type default)
			)
			(layer "B.Fab")
		)
		(fp_line
			(start 0.12065 -0.2794)
			(end -0.12065 -0.2794)
			(stroke
				(width 0.1)
				(type default)
			)
			(layer "B.Fab")
		)
		(fp_line
			(start -0.67945 -0.3048)
			(end -0.67945 0.3048)
			(stroke
				(width 0.1)
				(type default)
			)
			(layer "B.Fab")
		)
		(fp_line
			(start -0.12065 -0.3048)
			(end -0.67945 -0.3048)
			(stroke
				(width 0.1)
				(type default)
			)
			(layer "B.Fab")
		)
		(fp_line
			(start 0.12065 -0.305054)
			(end 0.12065 -0.2794)
			(stroke
				(width 0.1)
				(type default)
			)
			(layer "B.Fab")
		)
		(fp_line
			(start 0.67945 -0.305054)
			(end 0.12065 -0.305054)
			(stroke
				(width 0.1)
				(type default)
			)
			(layer "B.Fab")
		)
		(pad "1" smd circle
			(at 0.40005 0 90)
			(size 0 0)
			(layers "B.Cu" "B.Mask" "B.Paste")
			(net "P12V_HSC_SENSE2_N")
		)
		(pad "2" smd circle
			(at -0.40005 0 90)
			(size 0 0)
			(layers "B.Cu" "B.Mask" "B.Paste")
			(net "P12V_HSC_SENSE2_R2_N")
		)
	)
)
